(kicad_pcb
	(version 20240108)
	(generator "pcbnew")
	(generator_version "8.0")
	(general
		(thickness 1.62)
		(legacy_teardrops no)
	)
	(paper "A4")
	(title_block
		(title "Jetson Orin Baseboard")
		(date "2025-03-12")
		(rev "1.3.4")
		(company "Antmicro Ltd")
		(comment 1 "www.antmicro.com")
		(comment 9 "footprints 157-161 of 677")
	)
	(layers
		(0 "F.Cu" signal)
		(1 "In1.Cu" signal)
		(2 "In2.Cu" signal)
		(3 "In3.Cu" signal)
		(4 "In4.Cu" jumper)
		(5 "In5.Cu" signal)
		(6 "In6.Cu" signal)
		(31 "B.Cu" signal)
		(32 "B.Adhes" user "B.Adhesive")
		(33 "F.Adhes" user "F.Adhesive")
		(34 "B.Paste" user)
		(35 "F.Paste" user)
		(36 "B.SilkS" user "B.Silkscreen")
		(37 "F.SilkS" user "F.Silkscreen")
		(38 "B.Mask" user)
		(39 "F.Mask" user)
		(40 "Dwgs.User" user "User.Drawings")
		(41 "Cmts.User" user "User.Comments")
		(42 "Eco1.User" user "User.Eco1")
		(43 "Eco2.User" user "User.Eco2")
		(44 "Edge.Cuts" user)
		(45 "Margin" user)
		(46 "B.CrtYd" user "B.Courtyard")
		(47 "F.CrtYd" user "F.Courtyard")
		(48 "B.Fab" user)
		(49 "F.Fab" user)
	)
	(footprint "antmicro-footprints:C_0402_1005Metric"
		(layer "F.Cu")
		(at 140 113.485 -90)
		(descr "Capacitor SMD 0402")
		(tags "capacitor SMD 0402")
		(property "Reference" "C107"
			(at 1.365 0.475 -90)
			(layer "F.SilkS")
			(effects
				(font
					(size 0.7 0.7)
					(thickness 0.15)
				)
				(justify left bottom)
			)
		)
		(property "Value" "C_1u_0402"
			(at 0 1.4 -90)
			(layer "F.Fab")
			(effects
				(font
					(size 0.7 0.7)
					(thickness 0.15)
				)
				(justify left bottom)
			)
		)
		(property "Footprint" "antmicro-footprints:C_0402_1005Metric"
			(at 0 0 -90)
			(layer "F.Fab")
			(hide yes)
			(effects
				(font
					(size 1.27 1.27)
					(thickness 0.15)
				)
			)
		)
		(property "Datasheet" "https://product.tdk.com/en/search/capacitor/ceramic/mlcc/info?part_no=C1005X6S1A105K050BC"
			(at 0 0 -90)
			(layer "F.Fab")
			(hide yes)
			(effects
				(font
					(size 1.27 1.27)
					(thickness 0.15)
				)
			)
		)
		(property "Author" "Antmicro"
			(at 26.515 253.485 0)
			(layer "F.Fab")
			(hide yes)
			(effects
				(font
					(size 1 1)
					(thickness 0.15)
				)
			)
		)
		(property "Dielectric" ""
			(at 26.515 253.485 0)
			(layer "F.Fab")
			(hide yes)
			(effects
				(font
					(size 1 1)
					(thickness 0.15)
				)
			)
		)
		(property "License" "Apache-2.0"
			(at 26.515 253.485 0)
			(layer "F.Fab")
			(hide yes)
			(effects
				(font
					(size 1 1)
					(thickness 0.15)
				)
			)
		)
		(property "MPN" "C1005X6S1A105K050BC"
			(at 26.515 253.485 0)
			(layer "F.Fab")
			(hide yes)
			(effects
				(font
					(size 1 1)
					(thickness 0.15)
				)
			)
		)
		(property "Manufacturer" "TDK"
			(at 26.515 253.485 0)
			(layer "F.Fab")
			(hide yes)
			(effects
				(font
					(size 1 1)
					(thickness 0.15)
				)
			)
		)
		(property "Val" "1u"
			(at 26.515 253.485 0)
			(layer "F.Fab")
			(hide yes)
			(effects
				(font
					(size 1 1)
					(thickness 0.15)
				)
			)
		)
		(property "Voltage" ""
			(at 26.515 253.485 0)
			(layer "F.Fab")
			(hide yes)
			(effects
				(font
					(size 1 1)
					(thickness 0.15)
				)
			)
		)
		(sheetname "Peripherals")
		(sheetfile "peripherals.kicad_sch")
		(attr smd)
		(fp_rect
			(start -0.925 -0.47)
			(end 0.925 0.47)
			(stroke
				(width 0.05)
				(type default)
			)
			(fill none)
			(layer "F.CrtYd")
		)
		(fp_line
			(start -0.494 0.248)
			(end -0.494 -0.25)
			(stroke
				(width 0.15)
				(type solid)
			)
			(layer "F.Fab")
		)
		(fp_line
			(start 0.504 0.248)
			(end -0.494 0.248)
			(stroke
				(width 0.15)
				(type solid)
			)
			(layer "F.Fab")
		)
		(fp_line
			(start -0.494 -0.25)
			(end 0.504 -0.25)
			(stroke
				(width 0.15)
				(type solid)
			)
			(layer "F.Fab")
		)
		(fp_line
			(start 0.504 -0.25)
			(end 0.504 0.248)
			(stroke
				(width 0.15)
				(type solid)
			)
			(layer "F.Fab")
		)
		(fp_text user "License: Apache-2.0"
			(at -0.932 5.17 -90)
			(layer "F.Fab")
			(hide yes)
			(effects
				(font
					(size 0.7 0.7)
					(thickness 0.15)
				)
				(justify left bottom)
			)
		)
		(fp_text user "${REFERENCE}"
			(at -0.932 3.168 -90)
			(layer "F.Fab")
			(hide yes)
			(effects
				(font
					(size 0.7 0.7)
					(thickness 0.15)
				)
				(justify left bottom)
			)
		)
		(fp_text user "Author: Antmicro"
			(at -0.932 4.17 -90)
			(layer "F.Fab")
			(hide yes)
			(effects
				(font
					(size 0.7 0.7)
					(thickness 0.15)
				)
				(justify left bottom)
			)
		)
		(pad "1" smd roundrect
			(at -0.48 0 270)
			(size 0.59 0.64)
			(layers "F.Cu" "F.Paste" "F.Mask")
			(roundrect_rratio 0.25)
			(net 1 "GND")
			(pintype "passive")
		)
		(pad "2" smd roundrect
			(at 0.48 0 270)
			(size 0.59 0.64)
			(layers "F.Cu" "F.Paste" "F.Mask")
			(roundrect_rratio 0.25)
			(net 479 "/Peripherals/5V_CONN")
			(pintype "passive")
		)
	)
	(footprint "antmicro-footprints:XDFN-2_1x0.60mm"
		(layer "F.Cu")
		(at 147.45 86.9 90)
		(property "Reference" "D39"
			(at 6.29 -0.15 0)
			(layer "F.SilkS")
			(effects
				(font
					(size 0.7 0.7)
					(thickness 0.15)
				)
				(justify left bottom)
			)
		)
		(property "Value" "TPD1E0B04_XDFN-2"
			(at 0 1.5 90)
			(layer "F.Fab")
			(effects
				(font
					(size 0.7 0.7)
					(thickness 0.15)
				)
				(justify left bottom)
			)
		)
		(property "Footprint" "antmicro-footprints:XDFN-2_1x0.60mm"
			(at 0 0 90)
			(layer "F.Fab")
			(hide yes)
			(effects
				(font
					(size 1.27 1.27)
					(thickness 0.15)
				)
			)
		)
		(property "Datasheet" "https://www.ti.com/general/docs/suppproductinfo.tsp?distId=26&gotoUrl=https://www.ti.com/lit/gpn/tpd1e0b04"
			(at 0 0 90)
			(layer "F.Fab")
			(hide yes)
			(effects
				(font
					(size 1.27 1.27)
					(thickness 0.15)
				)
			)
		)
		(property "MPN" "TPD1E0B04DPYR"
			(at 234.35 -60.55 0)
			(layer "F.Fab")
			(hide yes)
			(effects
				(font
					(size 1 1)
					(thickness 0.15)
				)
			)
		)
		(property "Manufacturer" "Texas Instruments"
			(at 234.35 -60.55 0)
			(layer "F.Fab")
			(hide yes)
			(effects
				(font
					(size 1 1)
					(thickness 0.15)
				)
			)
		)
		(property "Author" "Antmicro"
			(at 234.35 -60.55 0)
			(layer "F.Fab")
			(hide yes)
			(effects
				(font
					(size 1 1)
					(thickness 0.15)
				)
			)
		)
		(property "License" "Apache-2.0"
			(at 234.35 -60.55 0)
			(layer "F.Fab")
			(hide yes)
			(effects
				(font
					(size 1 1)
					(thickness 0.15)
				)
			)
		)
		(sheetname "Peripherals")
		(sheetfile "peripherals.kicad_sch")
		(attr smd)
		(fp_rect
			(start -0.725 -0.475)
			(end 0.725 0.475)
			(stroke
				(width 0.05)
				(type solid)
			)
			(fill none)
			(layer "F.CrtYd")
		)
		(fp_rect
			(start -0.55 -0.35)
			(end 0.55 0.35)
			(stroke
				(width 0.15)
				(type solid)
			)
			(fill none)
			(layer "F.Fab")
		)
		(fp_text user "${REFERENCE}"
			(at -0.8 3.2 90)
			(layer "F.Fab")
			(hide yes)
			(effects
				(font
					(size 0.7 0.7)
					(thickness 0.15)
				)
				(justify left bottom)
			)
		)
		(fp_text user "License: Apache-2.0"
			(at -0.8 5.6 90)
			(layer "F.Fab")
			(hide yes)
			(effects
				(font
					(size 0.7 0.7)
					(thickness 0.15)
				)
				(justify left bottom)
			)
		)
		(fp_text user "Author: Antmicro"
			(at -0.8 4.4 90)
			(layer "F.Fab")
			(hide yes)
			(effects
				(font
					(size 0.7 0.7)
					(thickness 0.15)
				)
				(justify left bottom)
			)
		)
		(pad "1" smd roundrect
			(at -0.351 0 90)
			(size 0.3 0.5)
			(layers "F.Cu" "F.Paste" "F.Mask")
			(roundrect_rratio 0.25)
			(net 113 "PCIE2_RX0_N")
			(pinfunction "C")
			(pintype "passive")
		)
		(pad "2" smd roundrect
			(at 0.349 0 90)
			(size 0.3 0.5)
			(layers "F.Cu" "F.Paste" "F.Mask")
			(roundrect_rratio 0.25)
			(net 1 "GND")
			(pinfunction "A")
			(pintype "passive")
		)
	)
	(footprint "antmicro-footprints:R_Array_4x0201_Panasonic_EXB18V"
		(layer "F.Cu")
		(at 96.675 118.3)
		(property "Reference" "R35"
			(at -1.05 -0.725 180)
			(layer "F.SilkS")
			(effects
				(font
					(size 0.7 0.7)
					(thickness 0.15)
				)
				(justify left bottom)
			)
		)
		(property "Value" "R_4x0R_0201_array"
			(at -1.1 1.8 0)
			(layer "F.Fab")
			(effects
				(font
					(size 0.7 0.7)
					(thickness 0.15)
				)
				(justify left bottom)
			)
		)
		(property "Footprint" "antmicro-footprints:R_Array_4x0201_Panasonic_EXB18V"
			(at 0 0 0)
			(layer "F.Fab")
			(hide yes)
			(effects
				(font
					(size 1.27 1.27)
					(thickness 0.15)
				)
			)
		)
		(property "Datasheet" "http://industrial.panasonic.com/cdbs/www-data/pdf/AOC0000/AOC0000C14.pdf"
			(at 0 0 0)
			(layer "F.Fab")
			(hide yes)
			(effects
				(font
					(size 1.27 1.27)
					(thickness 0.15)
				)
			)
		)
		(property "Author" "Antmicro"
			(at 0 0 0)
			(layer "F.Fab")
			(hide yes)
			(effects
				(font
					(size 1 1)
					(thickness 0.15)
				)
			)
		)
		(property "License" "Apache-2.0"
			(at 0 0 0)
			(layer "F.Fab")
			(hide yes)
			(effects
				(font
					(size 1 1)
					(thickness 0.15)
				)
			)
		)
		(property "MPN" "EXB-18VR000X"
			(at 0 0 0)
			(layer "F.Fab")
			(hide yes)
			(effects
				(font
					(size 1 1)
					(thickness 0.15)
				)
			)
		)
		(property "Manufacturer" "Panasonic"
			(at 0 0 0)
			(layer "F.Fab")
			(hide yes)
			(effects
				(font
					(size 1 1)
					(thickness 0.15)
				)
			)
		)
		(property "Val" "4x0R_0201"
			(at 0 0 0)
			(layer "F.Fab")
			(hide yes)
			(effects
				(font
					(size 1 1)
					(thickness 0.15)
				)
			)
		)
		(sheetname "HDMI")
		(sheetfile "hdmi.kicad_sch")
		(attr smd)
		(fp_line
			(start -0.8 -0.45)
			(end -0.8 0.45)
			(stroke
				(width 0.12)
				(type solid)
			)
			(layer "F.SilkS")
		)
		(fp_line
			(start 0.8 -0.45)
			(end 0.8 0.45)
			(stroke
				(width 0.12)
				(type solid)
			)
			(layer "F.SilkS")
		)
		(fp_rect
			(start -0.898 -0.66)
			(end 0.898 0.65)
			(stroke
				(width 0.05)
				(type solid)
			)
			(fill none)
			(layer "F.CrtYd")
		)
		(fp_text user "${REFERENCE}"
			(at -1.051 3.2 0)
			(layer "F.Fab")
			(hide yes)
			(effects
				(font
					(size 0.7 0.7)
					(thickness 0.15)
				)
				(justify left bottom)
			)
		)
		(fp_text user "Author: Antmicro"
			(at -1.051 4.599 0)
			(layer "F.Fab")
			(hide yes)
			(effects
				(font
					(size 0.7 0.7)
					(thickness 0.15)
				)
				(justify left bottom)
			)
		)
		(fp_text user "License: Apache-2.0"
			(at -1.051 6 0)
			(layer "F.Fab")
			(hide yes)
			(effects
				(font
					(size 0.7 0.7)
					(thickness 0.15)
				)
				(justify left bottom)
			)
		)
		(pad "1" smd roundrect
			(at -0.6 0.298)
			(size 0.2 0.4)
			(layers "F.Cu" "F.Paste" "F.Mask")
			(roundrect_rratio 0.25)
			(net 525 "/HDMI/HDMI_D1_CONN_N")
			(pinfunction "R1.1")
			(pintype "passive")
		)
		(pad "2" smd roundrect
			(at -0.202 0.298)
			(size 0.2 0.4)
			(layers "F.Cu" "F.Paste" "F.Mask")
			(roundrect_rratio 0.25)
			(net 526 "/HDMI/HDMI_D1_CONN_P")
			(pinfunction "R2.1")
			(pintype "passive")
		)
		(pad "3" smd roundrect
			(at 0.2 0.298)
			(size 0.2 0.4)
			(layers "F.Cu" "F.Paste" "F.Mask")
			(roundrect_rratio 0.25)
			(net 527 "/HDMI/HDMI_D2_CONN_N")
			(pinfunction "R3.1")
			(pintype "passive")
		)
		(pad "4" smd roundrect
			(at 0.598 0.298)
			(size 0.2 0.4)
			(layers "F.Cu" "F.Paste" "F.Mask")
			(roundrect_rratio 0.25)
			(net 528 "/HDMI/HDMI_D2_CONN_P")
			(pinfunction "R4.1")
			(pintype "passive")
		)
		(pad "5" smd roundrect
			(at 0.598 -0.3)
			(size 0.2 0.4)
			(layers "F.Cu" "F.Paste" "F.Mask")
			(roundrect_rratio 0.25)
			(net 492 "/HDMI/HDMI_D2_P")
			(pinfunction "R4.2")
			(pintype "passive")
		)
		(pad "6" smd roundrect
			(at 0.2 -0.3)
			(size 0.2 0.4)
			(layers "F.Cu" "F.Paste" "F.Mask")
			(roundrect_rratio 0.25)
			(net 486 "/HDMI/HDMI_D2_N")
			(pinfunction "R3.2")
			(pintype "passive")
		)
		(pad "7" smd roundrect
			(at -0.202 -0.3)
			(size 0.2 0.4)
			(layers "F.Cu" "F.Paste" "F.Mask")
			(roundrect_rratio 0.25)
			(net 493 "/HDMI/HDMI_D1_P")
			(pinfunction "R2.2")
			(pintype "passive")
		)
		(pad "8" smd roundrect
			(at -0.6 -0.3)
			(size 0.2 0.4)
			(layers "F.Cu" "F.Paste" "F.Mask")
			(roundrect_rratio 0.25)
			(net 487 "/HDMI/HDMI_D1_N")
			(pinfunction "R1.2")
			(pintype "passive")
		)
	)
	(footprint "antmicro-footprints:TSOT23-6"
		(layer "F.Cu")
		(at 102.35 119.25 90)
		(property "Reference" "U18"
			(at 1.4 -2.75 90)
			(layer "F.SilkS")
			(effects
				(font
					(size 0.7 0.7)
					(thickness 0.15)
				)
				(justify left bottom)
			)
		)
		(property "Value" "AP22615A_TSOT26"
			(at 0 2.6 90)
			(layer "F.Fab")
			(effects
				(font
					(size 0.7 0.7)
					(thickness 0.15)
				)
				(justify left bottom)
			)
		)
		(property "Footprint" "antmicro-footprints:TSOT23-6"
			(at 0 0 90)
			(layer "F.Fab")
			(hide yes)
			(effects
				(font
					(size 1.27 1.27)
					(thickness 0.15)
				)
			)
		)
		(property "Datasheet" "https://www.mouser.com/datasheet/2/115/DIOD_S_A0008958405_1-2543193.pdf"
			(at 0 0 90)
			(layer "F.Fab")
			(hide yes)
			(effects
				(font
					(size 1.27 1.27)
					(thickness 0.15)
				)
			)
		)
		(property "Author" "Antmicro"
			(at 221.6 16.9 0)
			(layer "F.Fab")
			(hide yes)
			(effects
				(font
					(size 1 1)
					(thickness 0.15)
				)
			)
		)
		(property "License" "Apache-2.0"
			(at 221.6 16.9 0)
			(layer "F.Fab")
			(hide yes)
			(effects
				(font
					(size 1 1)
					(thickness 0.15)
				)
			)
		)
		(property "MPN" "AP22615AWU-7"
			(at 221.6 16.9 0)
			(layer "F.Fab")
			(hide yes)
			(effects
				(font
					(size 1 1)
					(thickness 0.15)
				)
			)
		)
		(property "Manufacturer" "Diodes Incorporated"
			(at 221.6 16.9 0)
			(layer "F.Fab")
			(hide yes)
			(effects
				(font
					(size 1 1)
					(thickness 0.15)
				)
			)
		)
		(sheetname "USB3")
		(sheetfile "usb3.kicad_sch")
		(attr smd)
		(fp_line
			(start -1 -1.5)
			(end -1 -1.375)
			(stroke
				(width 0.15)
				(type solid)
			)
			(layer "F.SilkS")
		)
		(fp_line
			(start 1 -1.497)
			(end -1 -1.5)
			(stroke
				(width 0.15)
				(type solid)
			)
			(layer "F.SilkS")
		)
		(fp_line
			(start 1 -1.497)
			(end 1 -1.375)
			(stroke
				(width 0.15)
				(type solid)
			)
			(layer "F.SilkS")
		)
		(fp_line
			(start 1 1.55)
			(end 1 1.4)
			(stroke
				(width 0.15)
				(type solid)
			)
			(layer "F.SilkS")
		)
		(fp_line
			(start 1 1.55)
			(end -1 1.55)
			(stroke
				(width 0.15)
				(type solid)
			)
			(layer "F.SilkS")
		)
		(fp_line
			(start -1 1.55)
			(end -1 1.4)
			(stroke
				(width 0.15)
				(type solid)
			)
			(layer "F.SilkS")
		)
		(fp_circle
			(center -1.44 -1.5)
			(end -1.39 -1.5)
			(stroke
				(width 0.15)
				(type solid)
			)
			(fill solid)
			(layer "F.SilkS")
		)
		(fp_rect
			(start 1.93 -1.7)
			(end -1.93 1.7)
			(stroke
				(width 0.05)
				(type solid)
			)
			(fill none)
			(layer "F.CrtYd")
		)
		(fp_line
			(start -0.45 -1.521)
			(end -0.876 -1.096)
			(stroke
				(width 0.15)
				(type solid)
			)
			(layer "F.Fab")
		)
		(fp_rect
			(start 0.875 1.528)
			(end -0.875 -1.525)
			(stroke
				(width 0.15)
				(type solid)
			)
			(fill none)
			(layer "F.Fab")
		)
		(fp_text user "${REFERENCE}"
			(at -1.93 3.8 90)
			(layer "F.Fab")
			(hide yes)
			(effects
				(font
					(size 0.7 0.7)
					(thickness 0.15)
				)
				(justify left bottom)
			)
		)
		(fp_text user "Author: Antmicro"
			(at -1.93 5 90)
			(layer "F.Fab")
			(hide yes)
			(effects
				(font
					(size 0.7 0.7)
					(thickness 0.15)
				)
				(justify left bottom)
			)
		)
		(fp_text user "License: Apache-2.0"
			(at -1.93 6.199 90)
			(layer "F.Fab")
			(hide yes)
			(effects
				(font
					(size 0.7 0.7)
					(thickness 0.15)
				)
				(justify left bottom)
			)
		)
		(pad "1" smd rect
			(at -1.301 -0.947)
			(size 0.7 1.2)
			(layers "F.Cu" "F.Paste" "F.Mask")
			(net 270 "/USB3/USBC1_VBUS")
			(pinfunction "OUT")
			(pintype "power_out")
		)
		(pad "2" smd rect
			(at -1.301 0.004)
			(size 0.7 1.2)
			(layers "F.Cu" "F.Paste" "F.Mask")
			(net 1 "GND")
			(pinfunction "GND")
			(pintype "power_in")
		)
		(pad "3" smd rect
			(at -1.301 0.954)
			(size 0.7 1.2)
			(layers "F.Cu" "F.Paste" "F.Mask")
			(net 508 "USBC1_FLG")
			(pinfunction "FLG")
			(pintype "output")
		)
		(pad "4" smd rect
			(at 1.299 0.954)
			(size 0.7 1.2)
			(layers "F.Cu" "F.Paste" "F.Mask")
			(net 625 "Net-(Q4-D)")
			(pinfunction "EN")
			(pintype "input")
		)
		(pad "5" smd rect
			(at 1.299 0.004)
			(size 0.7 1.2)
			(layers "F.Cu" "F.Paste" "F.Mask")
			(net 564 "/USB3/USBC1_ISET")
			(pinfunction "ISET")
			(pintype "passive")
		)
		(pad "6" smd rect
			(at 1.299 -0.947)
			(size 0.7 1.2)
			(layers "F.Cu" "F.Paste" "F.Mask")
			(net 99 "+5V")
			(pinfunction "IN")
			(pintype "power_in")
		)
	)
	(footprint "antmicro-footprints:R_0402_1005Metric"
		(layer "F.Cu")
		(at 61.6 107)
		(descr "Resistor SMD 0402")
		(tags "resistor SMD 0402")
		(property "Reference" "R78"
			(at 0.75 0.45 0)
			(layer "F.SilkS")
			(effects
				(font
					(size 0.7 0.7)
					(thickness 0.15)
				)
				(justify left bottom)
			)
		)
		(property "Value" "R_2k2_0402"
			(at 0 1.4 0)
			(layer "F.Fab")
			(effects
				(font
					(size 0.7 0.7)
					(thickness 0.15)
				)
				(justify left bottom)
			)
		)
		(property "Footprint" "antmicro-footprints:R_0402_1005Metric"
			(at 0 0 0)
			(layer "F.Fab")
			(hide yes)
			(effects
				(font
					(size 1.27 1.27)
					(thickness 0.15)
				)
			)
		)
		(property "Datasheet" "https://www.bourns.com/docs/product-datasheets/cr.pdf"
			(at 0 0 0)
			(layer "F.Fab")
			(hide yes)
			(effects
				(font
					(size 1.27 1.27)
					(thickness 0.15)
				)
			)
		)
		(property "Author" "Antmicro"
			(at 0 0 0)
			(layer "F.Fab")
			(hide yes)
			(effects
				(font
					(size 1 1)
					(thickness 0.15)
				)
			)
		)
		(property "License" "Apache-2.0"
			(at 0 0 0)
			(layer "F.Fab")
			(hide yes)
			(effects
				(font
					(size 1 1)
					(thickness 0.15)
				)
			)
		)
		(property "MPN" "CR0402-FX-2201GLF"
			(at 0 0 0)
			(layer "F.Fab")
			(hide yes)
			(effects
				(font
					(size 1 1)
					(thickness 0.15)
				)
			)
		)
		(property "Manufacturer" "Bourns"
			(at 0 0 0)
			(layer "F.Fab")
			(hide yes)
			(effects
				(font
					(size 1 1)
					(thickness 0.15)
				)
			)
		)
		(property "Tolerance" "1%"
			(at 0 0 0)
			(layer "F.Fab")
			(hide yes)
			(effects
				(font
					(size 1 1)
					(thickness 0.15)
				)
			)
		)
		(property "Val" "2k2"
			(at 0 0 0)
			(layer "F.Fab")
			(hide yes)
			(effects
				(font
					(size 1 1)
					(thickness 0.15)
				)
			)
		)
		(sheetname "USB Debug, DP")
		(sheetfile "usb.kicad_sch")
		(attr smd)
		(fp_rect
			(start -0.925 -0.47)
			(end 0.925 0.47)
			(stroke
				(width 0.05)
				(type default)
			)
			(fill none)
			(layer "F.CrtYd")
		)
		(fp_rect
			(start -0.5 -0.25)
			(end 0.5 0.25)
			(stroke
				(width 0.15)
				(type solid)
			)
			(fill none)
			(layer "F.Fab")
		)
		(fp_text user "License: Apache-2.0"
			(at -0.95 5.169 0)
			(layer "F.Fab")
			(hide yes)
			(effects
				(font
					(size 0.7 0.7)
					(thickness 0.15)
				)
				(justify left bottom)
			)
		)
		(fp_text user "${REFERENCE}"
			(at -0.95 3.168 0)
			(layer "F.Fab")
			(hide yes)
			(effects
				(font
					(size 0.7 0.7)
					(thickness 0.15)
				)
				(justify left bottom)
			)
		)
		(fp_text user "Author: Antmicro"
			(at -0.95 4.169 0)
			(layer "F.Fab")
			(hide yes)
			(effects
				(font
					(size 0.7 0.7)
					(thickness 0.15)
				)
				(justify left bottom)
			)
		)
		(pad "1" smd roundrect
			(at -0.48 0)
			(size 0.59 0.64)
			(layers "F.Cu" "F.Paste" "F.Mask")
			(roundrect_rratio 0.25)
			(net 1 "GND")
			(pintype "passive")
		)
		(pad "2" smd roundrect
			(at 0.48 0)
			(size 0.59 0.64)
			(layers "F.Cu" "F.Paste" "F.Mask")
			(roundrect_rratio 0.25)
			(net 672 "Net-(U9-ISET)")
			(pintype "passive")
		)
	)
)
